# T6G (Grand Teton) — schematic netlist excerpt (pin names and nets, part order shuffled) for the footprints in the layout excerpt that follows; sources: Cadence DE-HDL packaged netlist, KiCad conversion of 04192023_DAF0TMB3IC0_F0TG_MB_C_brd_V02_OCP.brd

R2830  Q_RES  100K 1% CHIP  pkg 0402LF  page 127 : A = P3V3_AUX ; B = BIC_MONITER
R1470  Q_RES  4.7K 5% EMPTY  pkg 0201LF  page 287 : A = P1V8_CPU0_RT_1D ; B = JTAG_TDI_RT_CPU0_P1
R499  Q_RES  4.7K 5% CHIP  pkg 0402LF  page 34 : A = P3V3_AUX ; B = SMB_CPU0_4_XLTR_SCL

(kicad_pcb
	(version 20260206)
	(generator "pcbnew")
	(generator_version "10.0")
	(general
		(thickness 1.6)
		(legacy_teardrops no)
	)
	(paper "A4")
	(title_block
		(title "04192023_DAF0TMB3IC0_F0TG_MB_C_brd_V02_OCP.brd")
		(comment 1 "Grand Teton / footprints 2668-2670 of 8354")
	)
	(layers
		(0 "F.Cu" signal "TOP")
		(4 "In1.Cu" signal "GND")
		(6 "In2.Cu" signal "IN1")
		(8 "In3.Cu" signal "GND1")
		(10 "In4.Cu" signal "IN2")
		(12 "In5.Cu" signal "GND2")
		(14 "In6.Cu" signal "IN3")
		(16 "In7.Cu" signal "GND3")
		(18 "In8.Cu" signal "VCC")
		(20 "In9.Cu" signal "VCC1")
		(22 "In10.Cu" signal "GND4")
		(24 "In11.Cu" signal "IN4")
		(26 "In12.Cu" signal "GND5")
		(28 "In13.Cu" signal "IN5")
		(30 "In14.Cu" signal "GND6")
		(32 "In15.Cu" signal "IN6")
		(34 "In16.Cu" signal "GND7")
		(2 "B.Cu" signal "BOTTOM")
		(9 "F.Adhes" user "F.Adhesive")
		(11 "B.Adhes" user "B.Adhesive")
		(13 "F.Paste" user "Package Geometry/Pastemask Top")
		(15 "B.Paste" user "Package Geometry/Pastemask Bottom")
		(5 "F.SilkS" user "Ref Des/Silkscreen Top")
		(7 "B.SilkS" user "Ref Des/Silkscreen Bottom")
		(1 "F.Mask" user "Board Geometry/Soldermask Top")
		(3 "B.Mask" user "Board Geometry/Soldermask Bottom")
		(17 "Dwgs.User" user "User.Drawings")
		(19 "Cmts.User" user "User.Comments")
		(21 "Eco1.User" user "User.Eco1")
		(23 "Eco2.User" user "User.Eco2")
		(25 "Edge.Cuts" user "Board Geometry/Outline")
		(27 "Margin" user)
		(31 "F.CrtYd" user "Package Geometry/Place Bound Top")
		(29 "B.CrtYd" user "Package Geometry/Place Bound Bottom")
		(35 "F.Fab" user "Ref Des/Assembly Top")
		(33 "B.Fab" user "Ref Des/Assembly Bottom")
	)
	(footprint ""
		(layer "F.Cu")
		(at 178.830224 -147.086574 90)
		(property "Reference" "R499"
			(at 0 0 90)
			(layer "F.SilkS")
			(hide yes)
			(effects
				(font
					(size 1.27 1.27)
				)
			)
		)
		(property "Value" ""
			(at 0 0 90)
			(layer "F.Fab")
			(effects
				(font
					(size 1.27 1.27)
				)
			)
		)
		(duplicate_pad_numbers_are_jumpers no)
		(fp_line
			(start 0.7874 -0.4064)
			(end 0.7874 0.4064)
			(stroke
				(width 0.1524)
				(type default)
			)
			(layer "F.SilkS")
		)
		(fp_line
			(start -0.7874 -0.4064)
			(end 0.7874 -0.4064)
			(stroke
				(width 0.1524)
				(type default)
			)
			(layer "F.SilkS")
		)
		(fp_line
			(start 0.7874 0.4064)
			(end -0.7874 0.4064)
			(stroke
				(width 0.1524)
				(type default)
			)
			(layer "F.SilkS")
		)
		(fp_line
			(start -0.7874 0.4064)
			(end -0.7874 -0.4064)
			(stroke
				(width 0.1524)
				(type default)
			)
			(layer "F.SilkS")
		)
		(fp_line
			(start -0.12065 -0.305054)
			(end -0.12065 -0.2794)
			(stroke
				(width 0.1)
				(type default)
			)
			(layer "F.Fab")
		)
		(fp_line
			(start -0.67945 -0.305054)
			(end -0.12065 -0.305054)
			(stroke
				(width 0.1)
				(type default)
			)
			(layer "F.Fab")
		)
		(fp_line
			(start 0.67945 -0.3048)
			(end 0.67945 0.3048)
			(stroke
				(width 0.1)
				(type default)
			)
			(layer "F.Fab")
		)
		(fp_line
			(start 0.12065 -0.3048)
			(end 0.67945 -0.3048)
			(stroke
				(width 0.1)
				(type default)
			)
			(layer "F.Fab")
		)
		(fp_line
			(start 0.12065 -0.2794)
			(end 0.12065 -0.3048)
			(stroke
				(width 0.1)
				(type default)
			)
			(layer "F.Fab")
		)
		(fp_line
			(start -0.12065 -0.2794)
			(end 0.12065 -0.2794)
			(stroke
				(width 0.1)
				(type default)
			)
			(layer "F.Fab")
		)
		(fp_line
			(start 0.120396 0.2794)
			(end -0.12065 0.2794)
			(stroke
				(width 0.1)
				(type default)
			)
			(layer "F.Fab")
		)
		(fp_line
			(start -0.12065 0.2794)
			(end -0.12065 0.3048)
			(stroke
				(width 0.1)
				(type default)
			)
			(layer "F.Fab")
		)
		(fp_line
			(start 0.67945 0.3048)
			(end 0.120396 0.3048)
			(stroke
				(width 0.1)
				(type default)
			)
			(layer "F.Fab")
		)
		(fp_line
			(start 0.120396 0.3048)
			(end 0.120396 0.2794)
			(stroke
				(width 0.1)
				(type default)
			)
			(layer "F.Fab")
		)
		(fp_line
			(start -0.12065 0.3048)
			(end -0.67945 0.3048)
			(stroke
				(width 0.1)
				(type default)
			)
			(layer "F.Fab")
		)
		(fp_line
			(start -0.67945 0.3048)
			(end -0.67945 -0.305054)
			(stroke
				(width 0.1)
				(type default)
			)
			(layer "F.Fab")
		)
		(pad "1" smd circle
			(at -0.40005 0 90)
			(size 0 0)
			(layers "F.Cu" "F.Mask" "F.Paste")
			(net "P3V3_AUX")
		)
		(pad "2" smd circle
			(at 0.40005 0 90)
			(size 0 0)
			(layers "F.Cu" "F.Mask" "F.Paste")
			(net "SMB_CPU0_4_XLTR_SCL")
		)
	)
	(footprint ""
		(layer "F.Cu")
		(at 163.4236 -440.182)
		(property "Reference" "R2830"
			(at 0 0 0)
			(layer "F.SilkS")
			(hide yes)
			(effects
				(font
					(size 1.27 1.27)
				)
			)
		)
		(property "Value" ""
			(at 0 0 0)
			(layer "F.Fab")
			(effects
				(font
					(size 1.27 1.27)
				)
			)
		)
		(duplicate_pad_numbers_are_jumpers no)
		(fp_line
			(start -0.7874 -0.4064)
			(end 0.7874 -0.4064)
			(stroke
				(width 0.1524)
				(type default)
			)
			(layer "F.SilkS")
		)
		(fp_line
			(start -0.7874 0.4064)
			(end -0.7874 -0.4064)
			(stroke
				(width 0.1524)
				(type default)
			)
			(layer "F.SilkS")
		)
		(fp_line
			(start 0.7874 -0.4064)
			(end 0.7874 0.4064)
			(stroke
				(width 0.1524)
				(type default)
			)
			(layer "F.SilkS")
		)
		(fp_line
			(start 0.7874 0.4064)
			(end -0.7874 0.4064)
			(stroke
				(width 0.1524)
				(type default)
			)
			(layer "F.SilkS")
		)
		(fp_line
			(start -0.67945 -0.305054)
			(end -0.12065 -0.305054)
			(stroke
				(width 0.1)
				(type default)
			)
			(layer "F.Fab")
		)
		(fp_line
			(start -0.67945 0.3048)
			(end -0.67945 -0.305054)
			(stroke
				(width 0.1)
				(type default)
			)
			(layer "F.Fab")
		)
		(fp_line
			(start -0.12065 -0.305054)
			(end -0.12065 -0.2794)
			(stroke
				(width 0.1)
				(type default)
			)
			(layer "F.Fab")
		)
		(fp_line
			(start -0.12065 -0.2794)
			(end 0.12065 -0.2794)
			(stroke
				(width 0.1)
				(type default)
			)
			(layer "F.Fab")
		)
		(fp_line
			(start -0.12065 0.2794)
			(end -0.12065 0.3048)
			(stroke
				(width 0.1)
				(type default)
			)
			(layer "F.Fab")
		)
		(fp_line
			(start -0.12065 0.3048)
			(end -0.67945 0.3048)
			(stroke
				(width 0.1)
				(type default)
			)
			(layer "F.Fab")
		)
		(fp_line
			(start 0.120396 0.2794)
			(end -0.12065 0.2794)
			(stroke
				(width 0.1)
				(type default)
			)
			(layer "F.Fab")
		)
		(fp_line
			(start 0.120396 0.3048)
			(end 0.120396 0.2794)
			(stroke
				(width 0.1)
				(type default)
			)
			(layer "F.Fab")
		)
		(fp_line
			(start 0.12065 -0.3048)
			(end 0.67945 -0.3048)
			(stroke
				(width 0.1)
				(type default)
			)
			(layer "F.Fab")
		)
		(fp_line
			(start 0.12065 -0.2794)
			(end 0.12065 -0.3048)
			(stroke
				(width 0.1)
				(type default)
			)
			(layer "F.Fab")
		)
		(fp_line
			(start 0.67945 -0.3048)
			(end 0.67945 0.3048)
			(stroke
				(width 0.1)
				(type default)
			)
			(layer "F.Fab")
		)
		(fp_line
			(start 0.67945 0.3048)
			(end 0.120396 0.3048)
			(stroke
				(width 0.1)
				(type default)
			)
			(layer "F.Fab")
		)
		(pad "1" smd circle
			(at -0.40005 0)
			(size 0 0)
			(layers "F.Cu" "F.Mask" "F.Paste")
			(net "P3V3_AUX")
		)
		(pad "2" smd circle
			(at 0.40005 0)
			(size 0 0)
			(layers "F.Cu" "F.Mask" "F.Paste")
			(net "BIC_MONITER")
		)
	)
	(footprint ""
		(layer "F.Cu")
		(at 351.4852 -407.8732 90)
		(property "Reference" "R1470"
			(at 0 0 90)
			(layer "F.SilkS")
			(hide yes)
			(effects
				(font
					(size 1.27 1.27)
				)
			)
		)
		(property "Value" ""
			(at 0 0 90)
			(layer "F.Fab")
			(effects
				(font
					(size 1.27 1.27)
				)
			)
		)
		(duplicate_pad_numbers_are_jumpers no)
		(fp_line
			(start 0.32512 -0.175006)
			(end 0.32512 0.175006)
			(stroke
				(width 0.1)
				(type default)
			)
			(layer "F.Fab")
		)
		(fp_line
			(start -0.32512 -0.175006)
			(end 0.32512 -0.175006)
			(stroke
				(width 0.1)
				(type default)
			)
			(layer "F.Fab")
		)
		(fp_line
			(start 0.32512 0.175006)
			(end -0.32512 0.175006)
			(stroke
				(width 0.1)
				(type default)
			)
			(layer "F.Fab")
		)
		(fp_line
			(start -0.32512 0.175006)
			(end -0.32512 -0.175006)
			(stroke
				(width 0.1)
				(type default)
			)
			(layer "F.Fab")
		)
		(pad "1" smd rect
			(at -0.2667 0 90)
			(size 0.3048 0.381)
			(layers "F.Cu" "F.Mask" "F.Paste")
			(net "P1V8_CPU0_RT_1D")
		)
		(pad "2" smd rect
			(at 0.2667 0 270)
			(size 0.3048 0.381)
			(layers "F.Cu" "F.Mask" "F.Paste")
			(net "JTAG_TDI_RT_CPU0_P1")
		)
	)
)
